# T6G (Grand Teton) — schematic netlist excerpt (pin names and nets, part order shuffled) for the footprints in the layout excerpt that follows; sources: Cadence DE-HDL packaged netlist, KiCad conversion of 04192023_DAF0TMB3IC0_F0TG_MB_C_brd_V02_OCP.brd

R1277  Q_RES  0 5% CHIP  pkg 0402LF  page 357 : A = SMB_INA230_7_3V3AUX_SDA_R ; B = SMB_INA230_7_3V3AUX_SDA_R1
R423  Q_RES  1K 1% EMPTY  pkg 0402LF  page 28 : A = PVDD11_S3_P0 ; B = I3C_0_SPD_DDRAF_CPU0_R_SDA

(kicad_pcb
	(version 20260206)
	(generator "pcbnew")
	(generator_version "10.0")
	(general
		(thickness 1.6)
		(legacy_teardrops no)
	)
	(paper "A4")
	(title_block
		(title "04192023_DAF0TMB3IC0_F0TG_MB_C_brd_V02_OCP.brd")
		(comment 1 "Grand Teton / footprints 3092-3093 of 8354")
	)
	(layers
		(0 "F.Cu" signal "TOP")
		(4 "In1.Cu" signal "GND")
		(6 "In2.Cu" signal "IN1")
		(8 "In3.Cu" signal "GND1")
		(10 "In4.Cu" signal "IN2")
		(12 "In5.Cu" signal "GND2")
		(14 "In6.Cu" signal "IN3")
		(16 "In7.Cu" signal "GND3")
		(18 "In8.Cu" signal "VCC")
		(20 "In9.Cu" signal "VCC1")
		(22 "In10.Cu" signal "GND4")
		(24 "In11.Cu" signal "IN4")
		(26 "In12.Cu" signal "GND5")
		(28 "In13.Cu" signal "IN5")
		(30 "In14.Cu" signal "GND6")
		(32 "In15.Cu" signal "IN6")
		(34 "In16.Cu" signal "GND7")
		(2 "B.Cu" signal "BOTTOM")
		(9 "F.Adhes" user "F.Adhesive")
		(11 "B.Adhes" user "B.Adhesive")
		(13 "F.Paste" user "Package Geometry/Pastemask Top")
		(15 "B.Paste" user "Package Geometry/Pastemask Bottom")
		(5 "F.SilkS" user "Ref Des/Silkscreen Top")
		(7 "B.SilkS" user "Ref Des/Silkscreen Bottom")
		(1 "F.Mask" user "Board Geometry/Soldermask Top")
		(3 "B.Mask" user "Board Geometry/Soldermask Bottom")
		(17 "Dwgs.User" user "User.Drawings")
		(19 "Cmts.User" user "User.Comments")
		(21 "Eco1.User" user "User.Eco1")
		(23 "Eco2.User" user "User.Eco2")
		(25 "Edge.Cuts" user "Board Geometry/Outline")
		(27 "Margin" user)
		(31 "F.CrtYd" user "Package Geometry/Place Bound Top")
		(29 "B.CrtYd" user "Package Geometry/Place Bound Bottom")
		(35 "F.Fab" user "Ref Des/Assembly Top")
		(33 "B.Fab" user "Ref Des/Assembly Bottom")
	)
	(footprint ""
		(layer "F.Cu")
		(at 319.405 -194.31)
		(property "Reference" "R423"
			(at 0 0 0)
			(layer "F.SilkS")
			(hide yes)
			(effects
				(font
					(size 1.27 1.27)
				)
			)
		)
		(property "Value" ""
			(at 0 0 0)
			(layer "F.Fab")
			(effects
				(font
					(size 1.27 1.27)
				)
			)
		)
		(duplicate_pad_numbers_are_jumpers no)
		(fp_line
			(start -0.7874 -0.4064)
			(end 0.7874 -0.4064)
			(stroke
				(width 0.1524)
				(type default)
			)
			(layer "F.SilkS")
		)
		(fp_line
			(start -0.7874 0.4064)
			(end -0.7874 -0.4064)
			(stroke
				(width 0.1524)
				(type default)
			)
			(layer "F.SilkS")
		)
		(fp_line
			(start 0.7874 -0.4064)
			(end 0.7874 0.4064)
			(stroke
				(width 0.1524)
				(type default)
			)
			(layer "F.SilkS")
		)
		(fp_line
			(start 0.7874 0.4064)
			(end -0.7874 0.4064)
			(stroke
				(width 0.1524)
				(type default)
			)
			(layer "F.SilkS")
		)
		(fp_line
			(start -0.67945 -0.305054)
			(end -0.12065 -0.305054)
			(stroke
				(width 0.1)
				(type default)
			)
			(layer "F.Fab")
		)
		(fp_line
			(start -0.67945 0.3048)
			(end -0.67945 -0.305054)
			(stroke
				(width 0.1)
				(type default)
			)
			(layer "F.Fab")
		)
		(fp_line
			(start -0.12065 -0.305054)
			(end -0.12065 -0.2794)
			(stroke
				(width 0.1)
				(type default)
			)
			(layer "F.Fab")
		)
		(fp_line
			(start -0.12065 -0.2794)
			(end 0.12065 -0.2794)
			(stroke
				(width 0.1)
				(type default)
			)
			(layer "F.Fab")
		)
		(fp_line
			(start -0.12065 0.2794)
			(end -0.12065 0.3048)
			(stroke
				(width 0.1)
				(type default)
			)
			(layer "F.Fab")
		)
		(fp_line
			(start -0.12065 0.3048)
			(end -0.67945 0.3048)
			(stroke
				(width 0.1)
				(type default)
			)
			(layer "F.Fab")
		)
		(fp_line
			(start 0.120396 0.2794)
			(end -0.12065 0.2794)
			(stroke
				(width 0.1)
				(type default)
			)
			(layer "F.Fab")
		)
		(fp_line
			(start 0.120396 0.3048)
			(end 0.120396 0.2794)
			(stroke
				(width 0.1)
				(type default)
			)
			(layer "F.Fab")
		)
		(fp_line
			(start 0.12065 -0.3048)
			(end 0.67945 -0.3048)
			(stroke
				(width 0.1)
				(type default)
			)
			(layer "F.Fab")
		)
		(fp_line
			(start 0.12065 -0.2794)
			(end 0.12065 -0.3048)
			(stroke
				(width 0.1)
				(type default)
			)
			(layer "F.Fab")
		)
		(fp_line
			(start 0.67945 -0.3048)
			(end 0.67945 0.3048)
			(stroke
				(width 0.1)
				(type default)
			)
			(layer "F.Fab")
		)
		(fp_line
			(start 0.67945 0.3048)
			(end 0.120396 0.3048)
			(stroke
				(width 0.1)
				(type default)
			)
			(layer "F.Fab")
		)
		(pad "1" smd circle
			(at -0.40005 0)
			(size 0 0)
			(layers "F.Cu" "F.Mask" "F.Paste")
			(net "PVDD11_S3_P0")
		)
		(pad "2" smd circle
			(at 0.40005 0)
			(size 0 0)
			(layers "F.Cu" "F.Mask" "F.Paste")
			(net "I3C_0_SPD_DDRAF_CPU0_R_SDA")
		)
	)
	(footprint ""
		(layer "F.Cu")
		(at 21.234654 -35.8013)
		(property "Reference" "R1277"
			(at 0 0 0)
			(layer "F.SilkS")
			(hide yes)
			(effects
				(font
					(size 1.27 1.27)
				)
			)
		)
		(property "Value" ""
			(at 0 0 0)
			(layer "F.Fab")
			(effects
				(font
					(size 1.27 1.27)
				)
			)
		)
		(duplicate_pad_numbers_are_jumpers no)
		(fp_line
			(start -0.7874 -0.4064)
			(end 0.7874 -0.4064)
			(stroke
				(width 0.1524)
				(type default)
			)
			(layer "F.SilkS")
		)
		(fp_line
			(start -0.7874 0.4064)
			(end -0.7874 -0.4064)
			(stroke
				(width 0.1524)
				(type default)
			)
			(layer "F.SilkS")
		)
		(fp_line
			(start 0.7874 -0.4064)
			(end 0.7874 0.4064)
			(stroke
				(width 0.1524)
				(type default)
			)
			(layer "F.SilkS")
		)
		(fp_line
			(start 0.7874 0.4064)
			(end -0.7874 0.4064)
			(stroke
				(width 0.1524)
				(type default)
			)
			(layer "F.SilkS")
		)
		(fp_line
			(start -0.67945 -0.305054)
			(end -0.12065 -0.305054)
			(stroke
				(width 0.1)
				(type default)
			)
			(layer "F.Fab")
		)
		(fp_line
			(start -0.67945 0.3048)
			(end -0.67945 -0.305054)
			(stroke
				(width 0.1)
				(type default)
			)
			(layer "F.Fab")
		)
		(fp_line
			(start -0.12065 -0.305054)
			(end -0.12065 -0.2794)
			(stroke
				(width 0.1)
				(type default)
			)
			(layer "F.Fab")
		)
		(fp_line
			(start -0.12065 -0.2794)
			(end 0.12065 -0.2794)
			(stroke
				(width 0.1)
				(type default)
			)
			(layer "F.Fab")
		)
		(fp_line
			(start -0.12065 0.2794)
			(end -0.12065 0.3048)
			(stroke
				(width 0.1)
				(type default)
			)
			(layer "F.Fab")
		)
		(fp_line
			(start -0.12065 0.3048)
			(end -0.67945 0.3048)
			(stroke
				(width 0.1)
				(type default)
			)
			(layer "F.Fab")
		)
		(fp_line
			(start 0.120396 0.2794)
			(end -0.12065 0.2794)
			(stroke
				(width 0.1)
				(type default)
			)
			(layer "F.Fab")
		)
		(fp_line
			(start 0.120396 0.3048)
			(end 0.120396 0.2794)
			(stroke
				(width 0.1)
				(type default)
			)
			(layer "F.Fab")
		)
		(fp_line
			(start 0.12065 -0.3048)
			(end 0.67945 -0.3048)
			(stroke
				(width 0.1)
				(type default)
			)
			(layer "F.Fab")
		)
		(fp_line
			(start 0.12065 -0.2794)
			(end 0.12065 -0.3048)
			(stroke
				(width 0.1)
				(type default)
			)
			(layer "F.Fab")
		)
		(fp_line
			(start 0.67945 -0.3048)
			(end 0.67945 0.3048)
			(stroke
				(width 0.1)
				(type default)
			)
			(layer "F.Fab")
		)
		(fp_line
			(start 0.67945 0.3048)
			(end 0.120396 0.3048)
			(stroke
				(width 0.1)
				(type default)
			)
			(layer "F.Fab")
		)
		(pad "1" smd circle
			(at -0.40005 0)
			(size 0 0)
			(layers "F.Cu" "F.Mask" "F.Paste")
			(net "SMB_INA230_7_3V3AUX_SDA_R")
		)
		(pad "2" smd circle
			(at 0.40005 0)
			(size 0 0)
			(layers "F.Cu" "F.Mask" "F.Paste")
			(net "SMB_INA230_7_3V3AUX_SDA_R1")
		)
	)
)
